# S9S_MB_2U (Grand Teton) — schematic netlist excerpt (pin names and nets, part order shuffled) for the footprints in the layout excerpt that follows; sources: Cadence DE-HDL packaged netlist, KiCad conversion of 03242023_DA0F0TMBIJ0_F0T_Motherboard_J_brd_V01_OCP.brd

PR1793  Q_RES  3.3 1% CHIP  pkg 0402LF  page 288 : A = SW_PVCCIN_CPU1_BOOT7 ; B = SW_PVCCIN_CPU1_BOOT7_R

(kicad_pcb
	(version 20260206)
	(generator "pcbnew")
	(generator_version "10.0")
	(general
		(thickness 1.6)
		(legacy_teardrops no)
	)
	(paper "A4")
	(title_block
		(title "03242023_DA0F0TMBIJ0_F0T_Motherboard_J_brd_V01_OCP.brd")
		(comment 1 "Grand Teton / footprints 3038-3038 of 6105")
	)
	(layers
		(0 "F.Cu" signal "TOP")
		(4 "In1.Cu" signal "GND")
		(6 "In2.Cu" signal "IN1")
		(8 "In3.Cu" signal "GND1")
		(10 "In4.Cu" signal "IN2")
		(12 "In5.Cu" signal "GND2")
		(14 "In6.Cu" signal "IN3")
		(16 "In7.Cu" signal "GND3")
		(18 "In8.Cu" signal "VCC")
		(20 "In9.Cu" signal "VCC1")
		(22 "In10.Cu" signal "GND4")
		(24 "In11.Cu" signal "IN4")
		(26 "In12.Cu" signal "GND5")
		(28 "In13.Cu" signal "IN5")
		(30 "In14.Cu" signal "GND6")
		(32 "In15.Cu" signal "IN6")
		(34 "In16.Cu" signal "GND7")
		(2 "B.Cu" signal "BOTTOM")
		(9 "F.Adhes" user "F.Adhesive")
		(11 "B.Adhes" user "B.Adhesive")
		(13 "F.Paste" user "Package Geometry/Pastemask Top")
		(15 "B.Paste" user "Package Geometry/Pastemask Bottom")
		(5 "F.SilkS" user "Ref Des/Silkscreen Top")
		(7 "B.SilkS" user "Ref Des/Silkscreen Bottom")
		(1 "F.Mask" user "Board Geometry/Soldermask Top")
		(3 "B.Mask" user "Board Geometry/Soldermask Bottom")
		(17 "Dwgs.User" user "User.Drawings")
		(19 "Cmts.User" user "User.Comments")
		(21 "Eco1.User" user "User.Eco1")
		(23 "Eco2.User" user "User.Eco2")
		(25 "Edge.Cuts" user "Board Geometry/Outline")
		(27 "Margin" user)
		(31 "F.CrtYd" user "Package Geometry/Place Bound Top")
		(29 "B.CrtYd" user "Package Geometry/Place Bound Bottom")
		(35 "F.Fab" user "Ref Des/Assembly Top")
		(33 "B.Fab" user "Ref Des/Assembly Bottom")
	)
	(footprint ""
		(layer "F.Cu")
		(at 81.435956 -347.520514 90)
		(property "Reference" "PR1793"
			(at 0 0 90)
			(layer "F.SilkS")
			(hide yes)
			(effects
				(font
					(size 1.27 1.27)
				)
			)
		)
		(property "Value" ""
			(at 0 0 90)
			(layer "F.Fab")
			(effects
				(font
					(size 1.27 1.27)
				)
			)
		)
		(duplicate_pad_numbers_are_jumpers no)
		(fp_line
			(start 0.7874 -0.4064)
			(end 0.7874 0.4064)
			(stroke
				(width 0.1524)
				(type default)
			)
			(layer "F.SilkS")
		)
		(fp_line
			(start -0.7874 -0.4064)
			(end 0.7874 -0.4064)
			(stroke
				(width 0.1524)
				(type default)
			)
			(layer "F.SilkS")
		)
		(fp_line
			(start 0.7874 0.4064)
			(end -0.7874 0.4064)
			(stroke
				(width 0.1524)
				(type default)
			)
			(layer "F.SilkS")
		)
		(fp_line
			(start -0.7874 0.4064)
			(end -0.7874 -0.4064)
			(stroke
				(width 0.1524)
				(type default)
			)
			(layer "F.SilkS")
		)
		(fp_line
			(start -0.12065 -0.305054)
			(end -0.12065 -0.2794)
			(stroke
				(width 0.1)
				(type default)
			)
			(layer "F.Fab")
		)
		(fp_line
			(start -0.67945 -0.305054)
			(end -0.12065 -0.305054)
			(stroke
				(width 0.1)
				(type default)
			)
			(layer "F.Fab")
		)
		(fp_line
			(start 0.67945 -0.3048)
			(end 0.67945 0.3048)
			(stroke
				(width 0.1)
				(type default)
			)
			(layer "F.Fab")
		)
		(fp_line
			(start 0.12065 -0.3048)
			(end 0.67945 -0.3048)
			(stroke
				(width 0.1)
				(type default)
			)
			(layer "F.Fab")
		)
		(fp_line
			(start 0.12065 -0.2794)
			(end 0.12065 -0.3048)
			(stroke
				(width 0.1)
				(type default)
			)
			(layer "F.Fab")
		)
		(fp_line
			(start -0.12065 -0.2794)
			(end 0.12065 -0.2794)
			(stroke
				(width 0.1)
				(type default)
			)
			(layer "F.Fab")
		)
		(fp_line
			(start 0.120396 0.2794)
			(end -0.12065 0.2794)
			(stroke
				(width 0.1)
				(type default)
			)
			(layer "F.Fab")
		)
		(fp_line
			(start -0.12065 0.2794)
			(end -0.12065 0.3048)
			(stroke
				(width 0.1)
				(type default)
			)
			(layer "F.Fab")
		)
		(fp_line
			(start 0.67945 0.3048)
			(end 0.120396 0.3048)
			(stroke
				(width 0.1)
				(type default)
			)
			(layer "F.Fab")
		)
		(fp_line
			(start 0.120396 0.3048)
			(end 0.120396 0.2794)
			(stroke
				(width 0.1)
				(type default)
			)
			(layer "F.Fab")
		)
		(fp_line
			(start -0.12065 0.3048)
			(end -0.67945 0.3048)
			(stroke
				(width 0.1)
				(type default)
			)
			(layer "F.Fab")
		)
		(fp_line
			(start -0.67945 0.3048)
			(end -0.67945 -0.305054)
			(stroke
				(width 0.1)
				(type default)
			)
			(layer "F.Fab")
		)
		(pad "1" smd circle
			(at -0.40005 0 90)
			(size 0 0)
			(layers "F.Cu" "F.Mask" "F.Paste")
			(net "SW_PVCCIN_CPU1_BOOT7")
		)
		(pad "2" smd circle
			(at 0.40005 0 90)
			(size 0 0)
			(layers "F.Cu" "F.Mask" "F.Paste")
			(net "SW_PVCCIN_CPU1_BOOT7_R")
		)
	)
)
